FILE_TYPE = MULTI_PHYS_TABLE;

PART 'Q_FUSE'

{========================================================================================}
:PACK_TYPE  | VALUE        | MATERIAL | PART_NUMBER              = STANDARD        | LIFECYCLE      | PART_NUMBER              | JEDEC_TYPE             | CLASS | DESCRIPTION                                     | COMPONENT_TYPE | LEAD_LENGTH | LPID | DAY        ;
{========================================================================================}
 'SMLF'     | '1.1A'       | 'IC'     | 'TMP_QDK110TPU110'(!)    = 'End of Design' | 'Comp-Approve' | 'DK110TPU110'            |'F1812'| 'IC'  | '1.1A'                                          | 'CHIP'         | ''          | ''   | ''        
 'SMLF'     | '1.1A'       | 'EMPTY'  | 'TMP_QDK110TPU110'(!)    = 'End of Design' | 'Comp-Approve' | 'DK110TPU110'            |'F1812'| 'IO'  | '1.1A'                                          | 'CHIP'         | ''          | ''   | ''        
 'SMLF'     | '4.5A'       | 'IC'     | 'TMP_QDK450WFU004'(!)    = ''              | ''             | 'DK450WFU004'            |'F1206'| 'IC'  | '4.5A'                                          | 'CHIP'         | ''          | ''   | ''        
 'SMLF'     | '4.5A'       | 'EMPTY'  | 'TMP_QDK450WFU004'(!)    = ''              | ''             | 'DK450WFU004'            |'F1206'| 'IO'  | '4.5A'                                          | 'CHIP'         | ''          | ''   | ''        
 'SMLF'     | '3A'         | 'IC'     | 'TMP_QDK300UFU000'(!)    = ''              | ''             | 'DK300UFU000'            |'F1206'| 'IC'  | '3A'                                            | 'CHIP'         | ''          | ''   | ''        
 'SMLF'     | '3A'         | 'EMPTY'  | 'TMP_QDK300UFU000'(!)    = ''              | ''             | 'DK300UFU000'            |'F1206'| 'IO'  | '3A'                                            | 'CHIP'         | ''          | ''   | ''        
 'SMLF'     | '5A/32V'     | 'IC'     | 'TMP_QDK500WFU011'(!)    = 'End of Design' | 'Comp-Approve' | 'DK500WFU011'            |'F1206'| 'IC'  | 'FUSE SMD 5A/ 32V/3216(FAST,UL/CSA)'            | 'CHIP'         | ''          | ''   | ''        
 'SMLF'     | '5A/32V'     | 'EMPTY'  | 'TMP_QDK500WFU011'(!)    = 'End of Design' | 'Comp-Approve' | 'DK500WFU011'            |'F1206'| 'IO'  | 'FUSE SMD 5A/ 32V/3216(FAST,UL/CSA)'            | 'CHIP'         | ''          | ''   | ''        
 'SMLF'     | '1.5A/63V'   | 'IC'     | 'TMP-C_S2I_0911_MASON_1'(!) = ''              | ''             | 'TMP-C_S2I_0911_MASON_1' |'F1206'| 'IC'  | 'FUSE SMD 1.5A 63V FAST(TR/3216FF1.5-R)'        | 'CHIP'         | ''          | ''   | ''        
 'SMLF'     | '1.5A/63V'   | 'EMPTY'  | 'TMP-C_S2I_0911_MASON_1'(!) = ''              | ''             | 'TMP-C_S2I_0911_MASON_1' |'F1206'| 'IO'  | 'FUSE SMD 1.5A 63V FAST(TR/3216FF1.5-R)'        | 'CHIP'         | ''          | ''   | ''        
 'SMLF'     | '1.6A/9V'    | 'IC'     | 'TMP_QDK160TPU113'(!)    = ''              | ''             | 'DK160TPU113'            |'F1812'| 'IC'  | 'FUSE SMD 1.6A 9V POLY(MINISMDC160F-2)'         | 'CHIP'         | ''          | ''   | ''        
 'SMLF'     | '1.6A/9V'    | 'EMPTY'  | 'TMP_QDK160TPU113'(!)    = ''              | ''             | 'DK160TPU113'            |'F1812'| 'IO'  | 'FUSE SMD 1.6A 9V POLY(MINISMDC160F-2)'         | 'CHIP'         | ''          | ''   | ''        
 'SMLF'     | '1.5A/6V'    | 'IC'     | 'QN-DK150TPU030'(!)      = 'End of Design' | 'Comp-Approve' | 'DK150TPU030'            |'F1206_H56'| 'IC'  | 'FUSE SMD 1.5A,6V(POLY,NANOSMDC150F-2)'         | 'CHIP'         | ''          | ''   | ''        
 'SMLF'     | '1.5A/6V'    | 'EMPTY'  | 'QN-DK150TPU030'(!)      = 'End of Design' | 'Comp-Approve' | 'DK150TPU030'            |'F1206_H56'| 'IO'  | 'FUSE SMD 1.5A,6V(POLY,NANOSMDC150F-2)'         | 'CHIP'         | ''          | ''   | ''        
 'SMLF'     | '3A/6V'      | 'IC'     | 'TMP-C_S2I_0421_MASON_1'(!) = ''              | ''             | 'TMP-C_S2I_0421_MASON_1' |'F2920_3'| 'IC'  | 'FUSE SMD 3A 6V POLY(SMD300F,UL/CSA)'           | 'CHIP'         | ''          | ''   | ''        
 'SMLF'     | '3A/6V'      | 'EMPTY'  | 'TMP-C_S2I_0421_MASON_1'(!) = ''              | ''             | 'TMP-C_S2I_0421_MASON_1' |'F2920_3'| 'IO'  | 'FUSE SMD 3A 6V POLY(SMD300F,UL/CSA)'           | 'CHIP'         | ''          | ''   | ''        
 'SMLF'     | '1.5A/6V'    | 'IC'     | 'TMP-C_S2I_0422_MASON_1'(!) = ''              | ''             | 'TMP-C_S2I_0422_MASON_1' |'F1206'| 'IC'  | 'FUSE SMD 1.5A 6V POLY(nanoSMDC150F,UL/CSA)'    | 'CHIP'         | ''          | ''   | ''        
 'SMLF'     | '1.5A/6V'    | 'EMPTY'  | 'TMP-C_S2I_0422_MASON_1'(!) = ''              | ''             | 'TMP-C_S2I_0422_MASON_1' |'F1206'| 'IO'  | 'FUSE SMD 1.5A 6V POLY(nanoSMDC150F,UL/CSA)'    | 'CHIP'         | ''          | ''   | ''        
 'SMLF'     | '0.5A/13.2V' | 'IC'     | 'TMP_QDK050SPU017'(!)    = 'End of Design' | 'Comp-Approve' | 'DK050SPU017'            |'F1206'| 'IC'  | 'FUSE SMD 0.5A,13.2V(POLY,NANOSMDC050F)'        | 'CHIP'         | ''          | ''   | ''        
 'SMLF'     | '0.5A/13.2V' | 'EMPTY'  | 'TMP_QDK050SPU017'(!)    = 'End of Design' | 'Comp-Approve' | 'DK050SPU017'            |'F1206'| 'IO'  | 'FUSE SMD 0.5A,13.2V(POLY,NANOSMDC050F)'        | 'CHIP'         | ''          | ''   | ''        
 'SMLF'     | '1.5A 32V'   | 'IC'     | 'TMP_QDK150WFU000'(!)    = 'End of Design' | 'Comp-Approve' | 'DK150WFU000'            |'F0603_H19'| 'IC'  | 'FUSE SMD 1.5A 32V(FAST,UL/CSA,0603)'           | 'CHIP'         | ''          | ''   | ''        
 'SMLF'     | '1.5A 32V'   | 'EMPTY'  | 'TMP_QDK150WFU000'(!)    = 'End of Design' | 'Comp-Approve' | 'DK150WFU000'            |'F0603_H19'| 'IO'  | 'FUSE SMD 1.5A 32V(FAST,UL/CSA,0603)'           | 'CHIP'         | ''          | ''   | ''        
 'SMLF'     | '6A,24V'     | 'IC'     | 'TMP_QDK600VPU004'(!)    = ''              | 'End of Life'  | 'DK600VPU004'            |'F1206_EOL'| 'IC'  | 'FUSE SMD 6A,24V POLY(1206SFS600F/24-2)'        | 'CHIP'         | ''          | ''   | ''        
 'SMLF'     | '6A,24V'     | 'EMPTY'  | 'TMP_QDK600VPU004'(!)    = ''              | 'End of Life'  | 'DK600VPU004'            |'F1206_EOL'| 'IO'  | 'FUSE SMD 6A,24V POLY(1206SFS600F/24-2)'        | 'CHIP'         | ''          | ''   | ''        
 'SMLF'     | '10A/125V'   | 'IC'     | 'TMP_QDKA00XFU409'(!)    = ''              | ''             | 'DKA00XFU409'            |'F2410'| 'IC'  | 'FUSE SMD 10A/125V(FAST,UL/CSA)'                | 'CHIP'         | ''          | ''   | ''        
 'SMLF'     | '10A/125V'   | 'EMPTY'  | 'TMP_QDKA00XFU409'(!)    = ''              | ''             | 'DKA00XFU409'            |'F2410'| 'IO'  | 'FUSE SMD 10A/125V(FAST,UL/CSA)'                | 'CHIP'         | ''          | ''   | ''        
 'SMLF'     | '.75A/13.2V' | 'IC'     | 'DK075SPU002'(!)         = ''              | ''             | 'DK075SPU002'            |'F1812'| 'IC'  | 'FUSE SMD .75A,13.2V(POLY,MINISMDC075F)LF'      | 'CHIP'         | ''          | ''   | ''        
 'SMLF'     | '.75A/13.2V' | 'EMPTY'  | 'DK075SPU002'(!)         = ''              | ''             | 'DK075SPU002'            |'F1812'| 'IO'  | 'FUSE SMD .75A,13.2V(POLY,MINISMDC075F)LF'      | 'CHIP'         | ''          | ''   | ''        
 'SMLF'     | '1.1A/16V'   | 'IC'     | 'DK110SPU001'(!)         = 'End of Design' | 'Comp-Approve' | 'DK110SPU001'            |'F1812'| 'IC'  | 'FUSE SMD 1.1A 16V POLY(MF-MSMF110/16)'         | 'CHIP'         | ''          | ''   | ''        
 'SMLF'     | '1.1A/16V'   | 'EMPTY'  | 'DK110SPU001'(!)         = 'End of Design' | 'Comp-Approve' | 'DK110SPU001'            |'F1812'| 'IO'  | 'FUSE SMD 1.1A 16V POLY(MF-MSMF110/16)'         | 'CHIP'         | ''          | ''   | ''        
 'SMLF'     | '3A/15V'     | 'IC'     | 'DK300SPU002'(!)         = ''              | ''             | 'DK300SPU002'            |'F2920_3'| 'IC'  | 'FUSE SMD 3A,15V,POLY(SMD300F/15)'              | 'CHIP'         | ''          | ''   | ''        
 'SMLF'     | '3A/15V'     | 'EMPTY'  | 'DK300SPU002'(!)         = ''              | ''             | 'DK300SPU002'            |'F2920_3'| 'IO'  | 'FUSE SMD 3A,15V,POLY(SMD300F/15)'              | 'CHIP'         | ''          | ''   | ''        
 'SMLF'     | '1.1A/8V'    | 'IC'     | 'DK110TPU012'(!)         = 'End of Design' | 'Comp-Approve' | 'DK110TPU012'            |'F1812'| 'IC'  | 'FUSE SMD 1.1A,8V(POLY,MINISMDC110F-2)'         | 'CHIP'         | ''          | ''   | '20101005'
 'SMLF'     | '1.1A/8V'    | 'EMPTY'  | 'DK110TPU012'(!)         = 'End of Design' | 'Comp-Approve' | 'DK110TPU012'            |'F1812'| 'IO'  | 'FUSE SMD 1.1A,8V(POLY,MINISMDC110F-2)'         | 'CHIP'         | ''          | ''   | '20101005'
 'SMLF'     | '1.5A/6V'    | 'IC'     | 'DK150TPU072'(!)         = ''              | 'End of Life'  | 'DK150TPU072'            |'F1206_EOL'| 'IC'  | 'FUSE SMD 1.5A,6V(POLY,1206L150PR)'             | 'CHIP'         | ''          | ''   | '20110207'
 'SMLF'     | '1.5A/6V'    | 'EMPTY'  | 'DK150TPU072'(!)         = ''              | 'End of Life'  | 'DK150TPU072'            |'F1206_EOL'| 'IO'  | 'FUSE SMD 1.5A,6V(POLY,1206L150PR)'             | 'CHIP'         | ''          | ''   | '20110207'
 'SMLF'     | '1.1A/6V'    | 'IC'     | 'DK110TPU501'(!)         = 'End of Design' | 'Comp-Approve' | 'DK110TPU501'            |'F1206'| 'IC'  | 'FUSE SMD 1.1A6V POLY(NANOSMDC110F-2)1206'      | 'CHIP'         | ''          | ''   | '20110217'
 'SMLF'     | '1.1A/6V'    | 'EMPTY'  | 'DK110TPU501'(!)         = 'End of Design' | 'Comp-Approve' | 'DK110TPU501'            |'F1206'| 'IO'  | 'FUSE SMD 1.1A6V POLY(NANOSMDC110F-2)1206'      | 'CHIP'         | ''          | ''   | '20110217'
 'SMLF'     | '5A/125V'    | 'IC'     | 'DK500XFU001'(!)         = ''              | ''             | 'DK500XFU001'            |'F2410'| 'IC'  | 'FUSE SMD 5A/125V(FAST,UL/CSA)0451005.MRL'      | 'CHIP'         | ''          | ''   | '20120224'
 'SMLF'     | '5A/125V'    | 'EMPTY'  | 'DK500XFU001'(!)         = ''              | ''             | 'DK500XFU001'            |'F2410'| 'IO'  | 'FUSE SMD 5A/125V(FAST,UL/CSA)0451005.MRL'      | 'CHIP'         | ''          | ''   | '20120224'
 'SMLF'     | '3A/15V'     | 'IC'     | 'DK300SPU000'(!)         = ''              | ''             | 'DK300SPU000'            |'F2920_1-25'| 'IC'  | 'FUSE SMD 3A 15V POLY(2920L300/15DR)'           | 'CHIP'         | ''          | ''   | '20120306'
 'SMLF'     | '3A/15V'     | 'EMPTY'  | 'DK300SPU000'(!)         = ''              | ''             | 'DK300SPU000'            |'F2920_1-25'| 'IO'  | 'FUSE SMD 3A 15V POLY(2920L300/15DR)'           | 'CHIP'         | ''          | ''   | '20120306'
 'SMLF'     | '2A/6V'      | 'IC'     | 'DK200TPU004'(!)         = 'End of Design' | 'Comp-Approve' | 'DK200TPU004'            |'F1206'| 'IC'  | 'FUSE SMD 2A 6V(POLY,UL/CSA,1206)'              | 'CHIP'         | ''          | ''   | '20120421'
 'SMLF'     | '2A/6V'      | 'EMPTY'  | 'DK200TPU004'(!)         = 'End of Design' | 'Comp-Approve' | 'DK200TPU004'            |'F1206'| 'IO'  | 'FUSE SMD 2A 6V(POLY,UL/CSA,1206)'              | 'CHIP'         | ''          | ''   | '20120421'
 'THLF'     | '9A/16V'     | 'IC'     | 'DK900SPU001'(!)         = ''              | ''             | 'DK900SPU001'            |'F1255_16R900GMR'| 'IC'  | 'FUSE DIP 9A/16V (POLY,UL/TUV)16R900GMR'        | 'CHIP'         | ''          | ''   | '20120314'
 'THLF'     | '9A/16V'     | 'EMPTY'  | 'DK900SPU001'(!)         = ''              | ''             | 'DK900SPU001'            |'F1255_16R900GMR'| 'IO'  | 'FUSE DIP 9A/16V (POLY,UL/TUV)16R900GMR'        | 'CHIP'         | ''          | ''   | '20120314'
 'THLF'     | '14A/16V'    | 'IC'     | 'DKE00SPU000'(!)         = ''              | ''             | 'DKE00SPU000'            |'F9314_16R1400GH'| 'IC'  | 'FUSE DIP 14A/16V(POLY,UL/TUV)16R1400GH'        | 'CHIP'         | ''          | ''   | '20120314'
 'THLF'     | '14A/16V'    | 'EMPTY'  | 'DKE00SPU000'(!)         = ''              | ''             | 'DKE00SPU000'            |'F9314_16R1400GH'| 'IO'  | 'FUSE DIP 14A/16V(POLY,UL/TUV)16R1400GH'        | 'CHIP'         | ''          | ''   | '20120314'
 'THLF_SEL' | '9A/16V'     | 'IC'     | 'SP_DK900SPU001'(!)      = ''              | ''             | 'DK900SPU001'            |'G_F1255_16R900GMR'| 'IC'  | 'FUSE DIP 9A/16V (POLY,UL/TUV)16R900GMR'        | 'CHIP'         | ''          | ''   | '20120314'
 'THLF_SEL' | '9A/16V'     | 'EMPTY'  | 'SP_DK900SPU001'(!)      = ''              | ''             | 'DK900SPU001'            |'G_F1255_16R900GMR'| 'IO'  | 'FUSE DIP 9A/16V (POLY,UL/TUV)16R900GMR'        | 'CHIP'         | ''          | ''   | '20120314'
 'THLF_SEL' | '14A/16V'    | 'IC'     | 'SP_DKE00SPU000'(!)      = ''              | ''             | 'DKE00SPU000'            |'G_F9314_16R1400GH'| 'IC'  | 'FUSE DIP 14A/16V(POLY,UL/TUV)16R1400GH'        | 'CHIP'         | ''          | ''   | '20120314'
 'THLF_SEL' | '14A/16V'    | 'EMPTY'  | 'SP_DKE00SPU000'(!)      = ''              | ''             | 'DKE00SPU000'            |'G_F9314_16R1400GH'| 'IO'  | 'FUSE DIP 14A/16V(POLY,UL/TUV)16R1400GH'        | 'CHIP'         | ''          | ''   | '20120314'
 'SMLF'     | '0.5A'       | 'IC'     | 'DK050SPU033'(!)         = ''              | ''             | 'DK050SPU033'            |'F1812'| 'IC'  | 'FUSE SMD 0.5A 15V POLY(SMD1812P050TF)'         | 'CHIP'         | ''          | ''   | '20120525'
 'SMLF'     | '0.5A'       | 'EMPTY'  | 'DK050SPU033'(!)         = ''              | ''             | 'DK050SPU033'            |'F1812'| 'IO'  | 'FUSE SMD 0.5A 15V POLY(SMD1812P050TF)'         | 'CHIP'         | ''          | ''   | '20120525'
 'SMLF'     | '2.6A'       | 'IC'     | 'DK260TPU001'(!)         = 'End of Design' | 'Comp-Approve' | 'DK260TPU001'            |'F1812'| 'IC'  | 'FUSE SMD 2.6A,6V(POLY,MINISMDC260F)'           | 'CHIP'         | ''          | ''   | '20120627'
 'SMLF'     | '2.6A'       | 'EMPTY'  | 'DK260TPU001'(!)         = 'End of Design' | 'Comp-Approve' | 'DK260TPU001'            |'F1812'| 'IO'  | 'FUSE SMD 2.6A,6V(POLY,MINISMDC260F)'           | 'CHIP'         | ''          | ''   | '20120627'
 'SMLF'     | '8A/32V'     | 'IC'     | 'DK800WFU000'(!)         = ''              | ''             | 'DK800WFU000'            |'F1206'| 'IC'  | 'FUSE SMD 8A 32V(FAST,0437008.WR,1206)'         | 'CHIP'         | ''          | ''   | '20120628'
 'SMLF'     | '8A/32V'     | 'EMPTY'  | 'DK800WFU000'(!)         = ''              | ''             | 'DK800WFU000'            |'F1206'| 'IO'  | 'FUSE SMD 8A 32V(FAST,0437008.WR,1206)'         | 'CHIP'         | ''          | ''   | '20120628'
 'SMLF'     | '3A/24V'     | 'IC'     | 'DK300VPU000'(!)         = 'End of Design' | 'Comp-Approve' | 'DK300VPU000'            |'F2920_1-6'| 'IC'  | 'FUSE SMD 3A 24V POLY(MF-LSMF300/24X-2)'        | 'CHIP'         | ''          | ''   | '20120706'
 'SMLF'     | '3A/24V'     | 'EMPTY'  | 'DK300VPU000'(!)         = 'End of Design' | 'Comp-Approve' | 'DK300VPU000'            |'F2920_1-6'| 'IO'  | 'FUSE SMD 3A 24V POLY(MF-LSMF300/24X-2)'        | 'CHIP'         | ''          | ''   | '20120706'
 'SMLF'     | '0.35A/6V'   | 'IC'     | 'DK035TPU000'(!)         = ''              | ''             | 'DK035TPU000'            |'F0603_H62'| 'IC'  | 'FUSE SMD 0.35A.6V(POLY.SMD0603P035TF)'         | 'CHIP'         | ''          | ''   | '20120914'
 'SMLF'     | '0.35A/6V'   | 'EMPTY'  | 'DK035TPU000'(!)         = ''              | ''             | 'DK035TPU000'            |'F0603_H62'| 'IO'  | 'FUSE SMD 0.35A.6V(POLY.SMD0603P035TF)'         | 'CHIP'         | ''          | ''   | '20120914'
 'SMLF'     | '1.1A/8V'    | 'IC'     | 'DK110TPU003'(!)         = ''              | ''             | 'DK110TPU003'            |'F1206'| 'IC'  | 'FUSE SMD 1.1A 8V POLY(SMD1206P110TFT)'         | 'CHIP'         | ''          | ''   | '20120915'
 'SMLF'     | '1.1A/8V'    | 'EMPTY'  | 'DK110TPU003'(!)         = ''              | ''             | 'DK110TPU003'            |'F1206'| 'IO'  | 'FUSE SMD 1.1A 8V POLY(SMD1206P110TFT)'         | 'CHIP'         | ''          | ''   | '20120915'
 'SMLF'     | '100ohm/4A'  | 'IC'     | 'CX12S101001'(!)         = 'End of Design' | 'End of Life'    | 'CX12S101001'            |'L0805_EOL'| 'IC'  | 'EMI FIL CHIP MPZ2012S101AT(100.4A)L-F'         | 'CHIP'         | ''          | ''   | '20121106'
 'SMLF'     | '100ohm/4A'  | 'EMPTY'  | 'CX12S101001'(!)         = 'End of Design' | 'End of Life'    | 'CX12S101001'            |'L0805_EOL'| 'IO'  | 'EMI FIL CHIP MPZ2012S101AT(100.4A)L-F'         | 'CHIP'         | ''          | ''   | '20121106'
 'SMLF'     | '6A/24V'     | 'IC'     | 'DK600VSU006'(!)         = 'End of Design' | 'End of Life'  | 'DK600VSU006'            |'F1206_EOL'| 'IC'  | 'FUSE SMD 6A 24V SLOW(1206SFS600F/24-2)'        | 'CHIP'         | ''          | ''   | '20130415'
 'SMLF'     | '6A/24V'     | 'EMPTY'  | 'DK600VSU006'(!)         = 'End of Design' | 'End of Life'  | 'DK600VSU006'            |'F1206_EOL'| 'IO'  | 'FUSE SMD 6A 24V SLOW(1206SFS600F/24-2)'        | 'CHIP'         | ''          | ''   | '20130415'
 'SMLF'     | '40A/60V'    | 'IC'     | 'DKZ00ZFU000'(!)         = ''              | ''             | 'DKZ00ZFU000'            |'F5018'| 'IC'  | 'FUSE SMD 40A/60V(FAST,UL/CSA)'                 | 'CHIP'         | ''          | ''   | '20130503'
 'SMLF'     | '40A/60V'    | 'EMPTY'  | 'DKZ00ZFU000'(!)         = ''              | ''             | 'DKZ00ZFU000'            |'F5018'| 'IO'  | 'FUSE SMD 40A/60V(FAST,UL/CSA)'                 | 'CHIP'         | ''          | ''   | '20130503'
 'SMLF'     | '25A/24V'    | 'IC'     | 'DKQ00VFU000'(!)         = ''              | ''             | 'DKQ00VFU000'            |'F1206XA'| 'IC'  | 'FUSE SMD 25A 24V(FAST.UL/CSA.1206)'            | 'CHIP'         | ''          | ''   | '20130509'
 'SMLF'     | '25A/24V'    | 'EMPTY'  | 'DKQ00VFU000'(!)         = ''              | ''             | 'DKQ00VFU000'            |'F1206XA'| 'IO'  | 'FUSE SMD 25A 24V(FAST.UL/CSA.1206)'            | 'CHIP'         | ''          | ''   | '20130509'
 'SMLF'     | '2.0A/8V'    | 'IC'     | 'DK200TPU001'(!)         = 'End of Design' | 'Comp-Approve' | 'DK200TPU001'            |'F1812XC'| 'IC'  | 'FUSE SMD 2.0A 8V POLY(MINISMDC200F-2)'         | 'CHIP'         | ''          | ''   | '20130527'
 'SMLF'     | '2.0A/8V'    | 'EMPTY'  | 'DK200TPU001'(!)         = 'End of Design' | 'Comp-Approve' | 'DK200TPU001'            |'F1812XC'| 'IO'  | 'FUSE SMD 2.0A 8V POLY(MINISMDC200F-2)'         | 'CHIP'         | ''          | ''   | '20130527'
 'SMLF'     | '15A/24V'    | 'IC'     | 'DKF00VFU003'(!)         = ''              | ''             | 'DKF00VFU003'            |'F1206XC'| 'IC'  | 'FUSE SMD 15A 24V(FAST,UL/CSA,1206)'            | 'CHIP'         | ''          | ''   | '20130605'
 'SMLF'     | '15A/24V'    | 'EMPTY'  | 'DKF00VFU003'(!)         = ''              | ''             | 'DKF00VFU003'            |'F1206XC'| 'IO'  | 'FUSE SMD 15A 24V(FAST,UL/CSA,1206)'            | 'CHIP'         | ''          | ''   | '20130605'
 'SMLF'     | '5A/24V'     | 'IC'     | 'DK500VFU113'(!)         = ''              | ''             | 'DK500VFU113'            |'F1206XB'| 'IC'  | 'FUSE SMD 5A/ 24V(FAST,UL/CSA)'                 | 'CHIP'         | ''          | ''   | '20130815'
 'SMLF'     | '5A/24V'     | 'EMPTY'  | 'DK500VFU113'(!)         = ''              | ''             | 'DK500VFU113'            |'F1206XB'| 'IO'  | 'FUSE SMD 5A/ 24V(FAST,UL/CSA)'                 | 'CHIP'         | ''          | ''   | '20130815'
 'SMLF'     | '0.55A/60V'  | 'IC'     | 'DK055ZPU000'(!)         = ''              | ''             | 'DK055ZPU000'            |'F2016'| 'IC'  | 'FUSE SMD 0.55A60V(POLY,UL/TUV)2016L050MR'      | 'CHIP'         | ''          | ''   | '20140212'
 'SMLF'     | '0.55A/60V'  | 'EMPTY'  | 'DK055ZPU000'(!)         = ''              | ''             | 'DK055ZPU000'            |'F2016'| 'IO'  | 'FUSE SMD 0.55A60V(POLY,UL/TUV)2016L050MR'      | 'CHIP'         | ''          | ''   | '20140212'
 'SMLF'     | '1.5A/24V'   | 'IC'     | 'DK150VPU027'(!)         = ''              | ''             | 'DK150VPU027'            |'F1812XA'| 'IC'  | 'FUSE SMD 1.5A 24V(POLY,UL/CSA/TUV)'            | 'CHIP'         | ''          | ''   | '20140227'
 'SMLF'     | '1.5A/24V'   | 'EMPTY'  | 'DK150VPU027'(!)         = ''              | ''             | 'DK150VPU027'            |'F1812XA'| 'IO'  | 'FUSE SMD 1.5A 24V(POLY,UL/CSA/TUV)'            | 'CHIP'         | ''          | ''   | '20140227'
 'SMLF'     | '45A/24V'    | 'IC'     | 'DKZ00VFU105'(!)         = ''              | 'End of Life'  | 'DKZ00VFU105'            |'F0603_H19_EOL'| 'IC'  | 'FUSE 45A 24V PGB1010603NR(0603)'               | 'CHIP'         | ''          | ''   | '20140227'
 'SMLF'     | '45A/24V'    | 'EMPTY'  | 'DKZ00VFU105'(!)         = ''              | 'End of Life'  | 'DKZ00VFU105'            |'F0603_H19_EOL'| 'IO'  | 'FUSE 45A 24V PGB1010603NR(0603)'               | 'CHIP'         | ''          | ''   | '20140227'
 'SMLF'     | '0.75A/6V'   | 'IC'     | 'DK075TPU031'(!)         = 'End of Design' | 'Comp-Approve' | 'DK075TPU031'            |'F1206XF'| 'IC'  | 'FUSE SMD 0.75A,6V(POLY,NANOSMDC075F-2)'        | 'CHIP'         | ''          | ''   | '20140227'
 'SMLF'     | '0.75A/6V'   | 'EMPTY'  | 'DK075TPU031'(!)         = 'End of Design' | 'Comp-Approve' | 'DK075TPU031'            |'F1206XF'| 'IO'  | 'FUSE SMD 0.75A,6V(POLY,NANOSMDC075F-2)'        | 'CHIP'         | ''          | ''   | '20140227'
 'SMLF'     | '3A/6V'      | 'IC'     | 'DK300TPU001'(!)         = ''              | ''             | 'DK300TPU001'            |'F1812XD'| 'IC'  | 'FUSE SMD 3A 6V POLY(MINISMDC300F)'             | 'CHIP'         | ''          | ''   | '20140227'
 'SMLF'     | '3A/6V'      | 'EMPTY'  | 'DK300TPU001'(!)         = ''              | ''             | 'DK300TPU001'            |'F1812XD'| 'IO'  | 'FUSE SMD 3A 6V POLY(MINISMDC300F)'             | 'CHIP'         | ''          | ''   | '20140227'
 'SMLF'     | '2A/15V'     | 'IC'     | 'DK200SPU000'(!)         = ''              | ''             | 'DK200SPU000'            |'F2920_1-25XA'| 'IC'  | 'FUSE SMD 2A,15V(POLY,2920L200PR)'              | 'CHIP'         | ''          | ''   | '20140331'
 'SMLF'     | '2A/15V'     | 'EMPTY'  | 'DK200SPU000'(!)         = ''              | ''             | 'DK200SPU000'            |'F2920_1-25XA'| 'IO'  | 'FUSE SMD 2A,15V(POLY,2920L200PR)'              | 'CHIP'         | ''          | ''   | '20140331'
 'SMLF'     | '8A/24V'     | 'IC'     | 'DK800VFU001'(!)         = 'End of Design' | 'Comp-Approve' | 'DK800VFU001'            |'F1206XG'| 'IC'  | 'FUSE SMD 8A/24V/F1206FA8000(FAST,UL/CSA)'      | 'CHIP'         | ''          | ''   | '20140403'
 'SMLF'     | '8A/24V'     | 'EMPTY'  | 'DK800VFU001'(!)         = 'End of Design' | 'Comp-Approve' | 'DK800VFU001'            |'F1206XG'| 'IO'  | 'FUSE SMD 8A/24V/F1206FA8000(FAST,UL/CSA)'      | 'CHIP'         | ''          | ''   | '20140403'
 'SMLF'     | '3A/24V'     | 'IC'     | 'DK300VPU001'(!)         = 'End of Design' | 'Comp-Approve' | 'DK300VPU001'            |'F2920_0-95'| 'IC'  | 'FUSE SMD 3A/24V(POLY,UL/CSA/TUV)'              | 'CHIP'         | ''          | ''   | '20140409'
 'SMLF'     | '3A/24V'     | 'EMPTY'  | 'DK300VPU001'(!)         = 'End of Design' | 'Comp-Approve' | 'DK300VPU001'            |'F2920_0-95'| 'IO'  | 'FUSE SMD 3A/24V(POLY,UL/CSA/TUV)'              | 'CHIP'         | ''          | ''   | '20140409'
 'SMLF'     | '0.75A/6V'   | 'IC'     | 'DK075TPU009'(!)         = ''              | ''             | 'DK075TPU009'            |'F0603_H30'| 'IC'  | 'FUSE SMD 0.75A 6V POLY(0603L075SLYR)'          | 'CHIP'         | ''          | ''   | '20140708'
 'SMLF'     | '0.75A/6V'   | 'EMPTY'  | 'DK075TPU009'(!)         = ''              | ''             | 'DK075TPU009'            |'F0603_H30'| 'IO'  | 'FUSE SMD 0.75A 6V POLY(0603L075SLYR)'          | 'CHIP'         | ''          | ''   | '20140708'
 'SMLF'     | '4.5A/6V'    | 'IC'     | 'DK450TPU000'(!)         = ''              | ''             | 'DK450TPU000'            |'F1210XA'| 'IC'  | 'FUSE SMD 4.5A 6V POLY(1210L450SLWR)'           | 'CHIP'         | ''          | ''   | '20140708'
 'SMLF'     | '4.5A/6V'    | 'EMPTY'  | 'DK450TPU000'(!)         = ''              | ''             | 'DK450TPU000'            |'F1210XA'| 'IO'  | 'FUSE SMD 4.5A 6V POLY(1210L450SLWR)'           | 'CHIP'         | ''          | ''   | '20140708'
 'SMLF'     | '2.82A/6V'   | 'IC'     | 'DK282TPU000'(!)         = ''              | ''             | 'DK282TPU000'            |'F1206XH'| 'IC'  | 'FUSE 2.82A 6V POLY UL/TUV(1206L380SLTH)'       | 'CHIP'         | ''          | ''   | '20141031'
 'SMLF'     | '2.82A/6V'   | 'EMPTY'  | 'DK282TPU000'(!)         = ''              | ''             | 'DK282TPU000'            |'F1206XH'| 'IO'  | 'FUSE 2.82A 6V POLY UL/TUV(1206L380SLTH)'       | 'CHIP'         | ''          | ''   | '20141031'
 'SMLF'     | '1A/6V'      | 'IC'     | 'DK100TPU004'(!)         = ''              | ''             | 'DK100TPU004'            |'F0603_H30'| 'IC'  | 'FUSE SMD 1A 6V POLY(SMD0603P100SLR)'           | 'CHIP'         | ''          | ''   | '20141218'
 'SMLF'     | '1A/6V'      | 'EMPTY'  | 'DK100TPU004'(!)         = ''              | ''             | 'DK100TPU004'            |'F0603_H30'| 'IO'  | 'FUSE SMD 1A 6V POLY(SMD0603P100SLR)'           | 'CHIP'         | ''          | ''   | '20141218'
 'THLF'     | '9.0A/16V'   | 'IC'     | 'DK900SPU000'(!)         = ''              | ''             | 'DK900SPU000'            |'F5512_RLD16P900GF'| 'IC'  | 'FUSE DIP 9.0A 16V POLY(RLD16P900GF)'           | 'CHIP'         | ''          | ''   | '20141218'
 'THLF'     | '9.0A/16V'   | 'EMPTY'  | 'DK900SPU000'(!)         = ''              | ''             | 'DK900SPU000'            |'F5512_RLD16P900GF'| 'IO'  | 'FUSE DIP 9.0A 16V POLY(RLD16P900GF)'           | 'CHIP'         | ''          | ''   | '20141218'
 'THLF'     | '9.0A/16V'   | 'IC'     | 'SP_DK900SPU000'(!)      = ''              | ''             | 'DK900SPU000'            |'G_F5512_RLD16P900GF'| 'IC'  | 'FUSE DIP 9.0A 16V POLY(RLD16P900GF)'           | 'CHIP'         | ''          | ''   | '20141218'
 'THLF'     | '9.0A/16V'   | 'EMPTY'  | 'SP_DK900SPU000'(!)      = ''              | ''             | 'DK900SPU000'            |'G_F5512_RLD16P900GF'| 'IO'  | 'FUSE DIP 9.0A 16V POLY(RLD16P900GF)'           | 'CHIP'         | ''          | ''   | '20141218'
 'SMLF'     | '5A/16V'     | 'IC'     | 'DK500SPU001'(!)         = ''              | ''             | 'DK500SPU001'            |'F2920_1-6'| 'IC'  | 'FUSE SMD 5A 16V POLY(2920L500/16MR)'           | 'CHIP'         | ''          | ''   | '20141223'
 'SMLF'     | '5A/16V'     | 'EMPTY'  | 'DK500SPU001'(!)         = ''              | ''             | 'DK500SPU001'            |'F2920_1-6'| 'IO'  | 'FUSE SMD 5A 16V POLY(2920L500/16MR)'           | 'CHIP'         | ''          | ''   | '20141223'
 'SMLF'     | '5A/16V'     | 'IC'     | 'DK500SPU002'(!)         = ''              | ''             | 'DK500SPU002'            |'F2920_1-6'| 'IC'  | 'FUSE SMD 5A 16V POLY(SMD2920P500TF/16)'        | 'CHIP'         | ''          | ''   | '20141223'
 'SMLF'     | '5A/16V'     | 'EMPTY'  | 'DK500SPU002'(!)         = ''              | ''             | 'DK500SPU002'            |'F2920_1-6'| 'IO'  | 'FUSE SMD 5A 16V POLY(SMD2920P500TF/16)'        | 'CHIP'         | ''          | ''   | '20141223'
 'SMLF'     | '4A/15V'     | 'IC'     | 'DK400SPU000'(!)         = ''              | ''             | 'DK400SPU000'            |'F2920_1-6'| 'IC'  | 'FUSE SMD 4A 15V POLY(SMD2920P400TF)'           | 'CHIP'         | ''          | ''   | '20141223'
 'SMLF'     | '4A/15V'     | 'EMPTY'  | 'DK400SPU000'(!)         = ''              | ''             | 'DK400SPU000'            |'F2920_1-6'| 'IO'  | 'FUSE SMD 4A 15V POLY(SMD2920P400TF)'           | 'CHIP'         | ''          | ''   | '20141223'
 'SMLF'     | '3.0A/15V'   | 'IC'     | 'DK300SPU001'(!)         = ''              | ''             | 'DK300SPU001'            |'F2920_1-25'| 'IC'  | 'FUSE 3.0A 15V POLY(SMD2920P300TF/15)'          | 'CHIP'         | ''          | ''   | '20141223'
 'SMLF'     | '3.0A/15V'   | 'EMPTY'  | 'DK300SPU001'(!)         = ''              | ''             | 'DK300SPU001'            |'F2920_1-25'| 'IO'  | 'FUSE 3.0A 15V POLY(SMD2920P300TF/15)'          | 'CHIP'         | ''          | ''   | '20141223'
 'SMLF'     | '1.5A/6V'    | 'IC'     | 'DK150TPU023'(!)         = ''              | ''             | 'DK150TPU023'            |'F0603_H40'| 'IC'  | 'FUSE SMD 1.5A 6V POLY(0603L150SLYR)'           | 'CHIP'         | ''          | ''   | '20141225'
 'SMLF'     | '1.5A/6V'    | 'EMPTY'  | 'DK150TPU023'(!)         = ''              | ''             | 'DK150TPU023'            |'F0603_H40'| 'IO'  | 'FUSE SMD 1.5A 6V POLY(0603L150SLYR)'           | 'CHIP'         | ''          | ''   | '20141225'
 'THLF'     | '11A/16V'    | 'IC'     | 'DKB00SPU000'(!)         = ''              | ''             | 'DKB00SPU000'            |'F6912_16R1100GMR'| 'IC'  | 'FUSE DIP 11A 16V POLY(16R1100GMR)'             | 'CHIP'         | ''          | ''   | '20141230'
 'THLF'     | '11A/16V'    | 'EMPTY'  | 'DKB00SPU000'(!)         = ''              | ''             | 'DKB00SPU000'            |'F6912_16R1100GMR'| 'IO'  | 'FUSE DIP 11A 16V POLY(16R1100GMR)'             | 'CHIP'         | ''          | ''   | '20141230'
 'SMLF'     | '1A/6V'      | 'IC'     | 'DK100TPU006'(!)         = ''              | ''             | 'DK100TPU006'            |'F0603_H30'| 'IC'  | 'FUSE SMD 1A 6V POLY(0603L100SLYR)'             | 'CHIP'         | ''          | ''   | '20150113'
 'SMLF'     | '1A/6V'      | 'EMPTY'  | 'DK100TPU006'(!)         = ''              | ''             | 'DK100TPU006'            |'F0603_H30'| 'IO'  | 'FUSE SMD 1A 6V POLY(0603L100SLYR)'             | 'CHIP'         | ''          | ''   | '20150113'
 'THLF'     | '8A/16V'     | 'IC'     | 'DK800SPU000'(!)         = ''              | ''             | 'DK800SPU000'            |'F5012_16R800G'| 'IC'  | 'FUSE DIP 8A/16V(POLY,UL/TUV)16R800GMR'         | 'CHIP'         | ''          | ''   | '20150202'
 'THLF'     | '8A/16V'     | 'EMPTY'  | 'DK800SPU000'(!)         = ''              | ''             | 'DK800SPU000'            |'F5012_16R800G'| 'IO'  | 'FUSE DIP 8A/16V(POLY,UL/TUV)16R800GMR'         | 'CHIP'         | ''          | ''   | '20150202'
 'THLF'     | '8A/16V'     | 'IC'     | 'SP_DK800SPU000'(!)      = ''              | ''             | 'DK800SPU000'            |'G_F5012_16R800G'| 'IC'  | 'FUSE DIP 8A/16V(POLY,UL/TUV)16R800GMR_FOR SEL' | 'CHIP'         | ''          | ''   | '20150202'
 'THLF'     | '8A/16V'     | 'EMPTY'  | 'SP_DK800SPU000'(!)      = ''              | ''             | 'DK800SPU000'            |'G_F5012_16R800G'| 'IO'  | 'FUSE DIP 8A/16V(POLY,UL/TUV)16R800GMR_FOR SEL' | 'CHIP'         | ''          | ''   | '20150202'
 'SMLF'     | '2.5A/16V'   | 'IC'     | 'DK250SPU000'(!)         = ''              | ''             | 'DK250SPU000'            |'F1812_2-25'| 'IC'  | 'FUSE SMD 2.5A 16V POLY(MF-MSMF250/16)'         | 'CHIP'         | ''          | ''   | '20150216'
 'SMLF'     | '2.5A/16V'   | 'EMPTY'  | 'DK250SPU000'(!)         = ''              | ''             | 'DK250SPU000'            |'F1812_2-25'| 'IO'  | 'FUSE SMD 2.5A 16V POLY(MF-MSMF250/16)'         | 'CHIP'         | ''          | ''   | '20150216'
 'SMLF'     | '5A/32V'     | 'IC'     | 'DK500WFU006'(!)         = ''              | ''             | 'DK500WFU006'            |'F0603_H19'| 'IC'  | 'FUSE SMD 5A 32V(FAST,0467005.NRHF,0603)'       | 'CHIP'         | ''          | ''   | '20150305'
 'SMLF'     | '5A/32V'     | 'EMPTY'  | 'DK500WFU006'(!)         = ''              | ''             | 'DK500WFU006'            |'F0603_H19'| 'IO'  | 'FUSE SMD 5A 32V(FAST,0467005.NRHF,0603)'       | 'CHIP'         | ''          | ''   | '20150305'
 'SMLF'     | '30A/250V'   | 'IC'     | 'DKV00YFU000'(!)         = ''              | ''             | 'DKV00YFU000'            |'F4012'| 'IC'  | 'FUSE SMD 30A 250V(FAST,UL)0463030.ER'          | 'CHIP'         | ''          | ''   | '20150331'
 'SMLF'     | '30A/250V'   | 'EMPTY'  | 'DKV00YFU000'(!)         = ''              | ''             | 'DKV00YFU000'            |'F4012'| 'IO'  | 'FUSE SMD 30A 250V(FAST,UL)0463030.ER'          | 'CHIP'         | ''          | ''   | '20150331'
 'SMLF'     | '0.05A/30V'  | 'IC'     | 'DK005WPU000'(!)         = 'End of Design' | 'Comp-Approve' | 'DK005WPU000'            |'F1210XA'| 'IC'  | 'FUSE SMD 0.05A 30V POLY(1210L005WR)'           | 'CHIP'         | ''          | ''   | '20150520'
 'SMLF'     | '0.05A/30V'  | 'EMPTY'  | 'DK005WPU000'(!)         = 'End of Design' | 'Comp-Approve' | 'DK005WPU000'            |'F1210XA'| 'IO'  | 'FUSE SMD 0.05A 30V POLY(1210L005WR)'           | 'CHIP'         | ''          | ''   | '20150520'
 'SMLF'     | '10A/63V'    | 'IC'     | 'DKA00UFU001'(!)         = ''              | ''             | 'DKA00UFU001'            |'F1206XE'| 'IC'  | 'FUSE SMD 10A 63V(FAST,UL,0458010.DR)'          | 'CHIP'         | ''          | ''   | '20150703'
 'SMLF'     | '10A/63V'    | 'EMPTY'  | 'DKA00UFU001'(!)         = ''              | ''             | 'DKA00UFU001'            |'F1206XE'| 'IO'  | 'FUSE SMD 10A 63V(FAST,UL,0458010.DR)'          | 'CHIP'         | ''          | ''   | '20150703'
 'SMLF'     | '2A/6V'      | 'IC'     | 'DK200TPU007'(!)         = ''              | ''             | 'DK200TPU007'            |'F1206XF_H44'| 'IC'  | 'FUSE SMD 2A 6V POLY (NANOSMDC200F)'            | 'CHIP'         | ''          | ''   | '20150811'
 'SMLF'     | '2A/6V'      | 'EMPTY'  | 'DK200TPU007'(!)         = ''              | ''             | 'DK200TPU007'            |'F1206XF_H44'| 'IO'  | 'FUSE SMD 2A 6V POLY (NANOSMDC200F)'            | 'CHIP'         | ''          | ''   | '20150811'
 'SMLF'     | '6.3A/75V'   | 'IC'     | 'DK630UFU000'(!)         = ''              | ''             | 'DK630UFU000'            |'F1206XE'| 'IC'  | 'FUSE SMD 6.3A 75V (FAST,UL)045806.3DR'         | 'CHIP'         | ''          | ''   | '20150922'
 'SMLF'     | '6.3A/75V'   | 'EMPTY'  | 'DK630UFU000'(!)         = ''              | ''             | 'DK630UFU000'            |'F1206XE'| 'IO'  | 'FUSE SMD 6.3A 75V (FAST,UL)045806.3DR'         | 'CHIP'         | ''          | ''   | '20150922'
 'SMLF'     | '3A/75V'     | 'IC'     | 'DK300UFU003'(!)         = ''              | ''             | 'DK300UFU003'            |'F1206XE'| 'IC'  | 'FUSE SMD 3A 75V (FAST,UL)0458003.DR'           | 'CHIP'         | ''          | ''   | '20150922'
 'SMLF'     | '3A/75V'     | 'EMPTY'  | 'DK300UFU003'(!)         = ''              | ''             | 'DK300UFU003'            |'F1206XE'| 'IO'  | 'FUSE SMD 3A 75V (FAST,UL)0458003.DR'           | 'CHIP'         | ''          | ''   | '20150922'
 'THLF'     | '8A/16V'     | 'IC'     | 'DK800SPU001'(!)         = ''              | ''             | 'DK800SPU001'            |'F5012_16R800G_H989'| 'IC'  | 'FUSE DIP 8A 16V POLY(16R800GKLMR)'             | 'CHIP'         | ''          | ''   | '20151117'
 'THLF'     | '8A/16V'     | 'EMPTY'  | 'DK800SPU001'(!)         = ''              | ''             | 'DK800SPU001'            |'F5012_16R800G_H989'| 'IO'  | 'FUSE DIP 8A 16V POLY(16R800GKLMR)'             | 'CHIP'         | ''          | ''   | '20151117'
 'THLF'     | '8A/16V'     | 'IC'     | 'SP_DK800SPU001'(!)      = ''              | ''             | 'SP_DK800SPU001'         |'G_F5012_16R800G_H989'| 'IC'  | 'FUSE DIP 8A 16V POLY(16R800GKLMR)_FOR SEL'     | 'CHIP'         | ''          | ''   | '20151117'
 'THLF'     | '8A/16V'     | 'EMPTY'  | 'SP_DK800SPU001'(!)      = ''              | ''             | 'SP_DK800SPU001'         |'G_F5012_16R800G_H989'| 'IO'  | 'FUSE DIP 8A 16V POLY(16R800GKLMR)_FOR SEL'     | 'CHIP'         | ''          | ''   | '20151117'
 'SMLF'     | '1A/32V'     | 'IC'     | 'DK100WFU009'(!)         = ''              | ''             | 'DK100WFU009'            |'F0603XA'| 'IC'  | 'FUSE SMD 1A 32V(FAST)F0603FA1000V03'           | 'CHIP'         | ''          | ''   | '20151222'
 'SMLF'     | '1A/32V'     | 'EMPTY'  | 'DK100WFU009'(!)         = ''              | ''             | 'DK100WFU009'            |'F0603XA'| 'IO'  | 'FUSE SMD 1A 32V(FAST)F0603FA1000V03'           | 'CHIP'         | ''          | ''   | '20151222'
 'SMLF'     | '3A/32V'     | 'IC'     | 'DK300WFU006'(!)         = ''              | ''             | 'DK300WFU006'            |'F0603XA'| 'IC'  | 'FUSE SMD 3A/32V(FAST,UL)F0603FA3000V032T'      | 'CHIP'         | ''          | ''   | '20151222'
 'SMLF'     | '3A/32V'     | 'EMPTY'  | 'DK300WFU006'(!)         = ''              | ''             | 'DK300WFU006'            |'F0603XA'| 'IO'  | 'FUSE SMD 3A/32V(FAST,UL)F0603FA3000V032T'      | 'CHIP'         | ''          | ''   | '20151222'
 'SMLF'     | '5A/32V'     | 'IC'     | 'DK800WFU004'(!)         = 'End of Design' | 'Comp-Approve' | 'DK800WFU004'            |'F0603XA'| 'IC'  | 'FUSE SMD 5A/32V/0603FA5000V032T(FAST,UL)'      | 'CHIP'         | ''          | ''   | '20151222'
 'SMLF'     | '5A/32V'     | 'EMPTY'  | 'DK800WFU004'(!)         = 'End of Design' | 'Comp-Approve' | 'DK800WFU004'            |'F0603XA'| 'IO'  | 'FUSE SMD 5A/32V/0603FA5000V032T(FAST,UL)'      | 'CHIP'         | ''          | ''   | '20151222'
 'SMLF'     | '1.5A/63V'   | 'IC'     | 'DK150UFU002'(!)         = ''              | ''             | 'DK150UFU002'            |'F0603XA'| 'IC'  | 'FUSE SMD 1.5A 63V(FAST,UL)F0603FA1500V06'      | 'CHIP'         | ''          | ''   | '20151223'
 'SMLF'     | '1.5A/63V'   | 'EMPTY'  | 'DK150UFU002'(!)         = ''              | ''             | 'DK150UFU002'            |'F0603XA'| 'IO'  | 'FUSE SMD 1.5A 63V(FAST,UL)F0603FA1500V06'      | 'CHIP'         | ''          | ''   | '20151223'
 'SMLF'     | '10A/32V'    | 'IC'     | 'DKA00WFU000'(!)         = ''              | ''             | 'DKA00WFU000'            |'F1206XG'| 'IC'  | 'FUSE SMD10A/32V/AF1206F10.0(FAST,UL/CSA)'      | 'CHIP'         | ''          | ''   | '20160113'
 'SMLF'     | '10A/32V'    | 'EMPTY'  | 'DKA00WFU000'(!)         = ''              | ''             | 'DKA00WFU000'            |'F1206XG'| 'IO'  | 'FUSE SMD10A/32V/AF1206F10.0(FAST,UL/CSA)'      | 'CHIP'         | ''          | ''   | '20160113'
 'SMLF'     | '20A/24V'    | 'IC'     | 'DKK00VFU001'(!)         = ''              | ''             | 'DKK00VFU001'            |'F1206XG'| 'IC'  | 'FUSE SMD 20A 24V(FAST) 1206SFH200F/24'         | 'CHIP'         | ''          | ''   | '20160218'
 'SMLF'     | '20A/24V'    | 'EMPTY'  | 'DKK00VFU001'(!)         = ''              | ''             | 'DKK00VFU001'            |'F1206XG'| 'IO'  | 'FUSE SMD 20A 24V(FAST) 1206SFH200F/24'         | 'CHIP'         | ''          | ''   | '20160218'
 'SMLF'     | '5A/16V'     | 'IC'     | 'DK500SPU004'(!)         = ''              | ''             | 'DK500SPU004'            |'F4112_16R500GPR'| 'IC'  | 'FUSE DIP 5A/16V(POLY,UL/TUV)16R500GPR'         | 'CHIP'         | ''          | ''   | '20160223'
 'SMLF'     | '5A/16V'     | 'EMPTY'  | 'DK500SPU004'(!)         = ''              | ''             | 'DK500SPU004'            |'F4112_16R500GPR'| 'IO'  | 'FUSE DIP 5A/16V(POLY,UL/TUV)16R500GPR'         | 'CHIP'         | ''          | ''   | '20160223'
 'SMLF'     | '5A/16V'     | 'IC'     | 'SP_DK500SPU004'(!)      = ''              | ''             | 'DK500SPU004'            |'G_F4112_16R500GPR'| 'IC'  | 'FUSE DIP 5A/16V(POLY,UL/TUV)16R500GPR_FOR SEL' | 'CHIP'         | ''          | ''   | '20160223'
 'SMLF'     | '5A/16V'     | 'EMPTY'  | 'SP_DK500SPU004'(!)      = ''              | ''             | 'DK500SPU004'            |'G_F4112_16R500GPR'| 'IO'  | 'FUSE DIP 5A/16V(POLY,UL/TUV)16R500GPR_FOR SEL' | 'CHIP'         | ''          | ''   | '20160223'
 'SMLF'     | '15A/125V'   | 'IC'     | 'DKF00XFU001'(!)         = ''              | ''             | 'DKF00XFU001'            |'F2410XA'| 'IC'  | 'FUSE SMD 15A 125V(FAST,UL/PSE)CB61F15A'        | 'CHIP'         | ''          | ''   | '20160225'
 'SMLF'     | '15A/125V'   | 'EMPTY'  | 'DKF00XFU001'(!)         = ''              | ''             | 'DKF00XFU001'            |'F2410XA'| 'IO'  | 'FUSE SMD 15A 125V(FAST,UL/PSE)CB61F15A'        | 'CHIP'         | ''          | ''   | '20160225'
 'SMLF'     | '1.5A/125V'  | 'IC'     | 'DK150XFU000'(!)         = 'End of Design' | 'End of Life'  | 'DK150XFU000'            |'F2410XA_EOL'| 'IC'  | 'FUSE SMD 1.5A/125V(FAST,UL/CSA/CE)SSQ1.5'      | 'CHIP'         | ''          | ''   | '20160225'
 'SMLF'     | '1.5A/125V'  | 'EMPTY'  | 'DK150XFU000'(!)         = 'End of Design' | 'End of Life'  | 'DK150XFU000'            |'F2410XA_EOL'| 'IO'  | 'FUSE SMD 1.5A/125V(FAST,UL/CSA/CE)SSQ1.5'      | 'CHIP'         | ''          | ''   | '20160225'
 'SMLF'     | '15A/125V'   | 'IC'     | 'DKF00VFU004'(!)         = 'End of Design' | 'End of Life'  | 'DKF00VFU004'            |'F2410XA_EOL'| 'IC'  | 'FUSE SMD 15A/125V(FAST,UL/CSA)SSQ 15'          | 'CHIP'         | ''          | ''   | '20160225'
 'SMLF'     | '15A/125V'   | 'EMPTY'  | 'DKF00VFU004'(!)         = 'End of Design' | 'End of Life'  | 'DKF00VFU004'            |'F2410XA_EOL'| 'IO'  | 'FUSE SMD 15A/125V(FAST,UL/CSA)SSQ 15'          | 'CHIP'         | ''          | ''   | '20160225'
 'SMLF'     | '10A/125V'   | 'IC'     | 'DKA00XFU002'(!)         = 'Non-Preferred' | 'End of Life'  | 'DKA00XFU002'            |'F2410XA_EOL'| 'IC'  | 'FUSE SMD 10A 125V(FAST,SSQ10)'                 | 'CHIP'         | ''          | ''   | '20160301'
 'SMLF'     | '10A/125V'   | 'EMPTY'  | 'DKA00XFU002'(!)         = 'Non-Preferred' | 'End of Life'  | 'DKA00XFU002'            |'F2410XA_EOL'| 'IO'  | 'FUSE SMD 10A 125V(FAST,SSQ10)'                 | 'CHIP'         | ''          | ''   | '20160301'
 'SMLF'     | '15A/125V'   | 'IC'     | 'DKF00XFU002'(!)         = ''              | ''             | 'DKF00XFU002'            |'F2410'| 'IC'  | 'FUSE SMD 15A/125V(FAST,UL)0476015.MRSN'        | 'CHIP'         | ''          | ''   | '20160324'
 'SMLF'     | '15A/125V'   | 'EMPTY'  | 'DKF00XFU002'(!)         = ''              | ''             | 'DKF00XFU002'            |'F2410'| 'IO'  | 'FUSE SMD 15A/125V(FAST,UL)0476015.MRSN'        | 'CHIP'         | ''          | ''   | '20160324'
 'SMLF'     | '5A/32V'     | 'IC'     | 'DK500WFU008'(!)         = 'End of Design' | 'End of Life'  | 'DK500WFU008'            |'F0603XB_EOL'| 'IC'  | 'FUSE SMD 5A 32V(FAST,0438005.WR,0603)'         | 'CHIP'         | ''          | ''   | '20160324'
 'SMLF'     | '5A/32V'     | 'EMPTY'  | 'DK500WFU008'(!)         = 'End of Design' | 'End of Life'  | 'DK500WFU008'            |'F0603XB_EOL'| 'IO'  | 'FUSE SMD 5A 32V(FAST,0438005.WR,0603)'         | 'CHIP'         | ''          | ''   | '20160324'
 'SMLF'     | '3A/32V'     | 'IC'     | 'DK300WFU011'(!)         = 'End of Design' | 'End of Life'  | 'DK300WFU011'            |'F0603XB_EOL'| 'IC'  | 'FUSE SMD 3A 32V(FAST,0438003.WR,0603)'         | 'CHIP'         | ''          | ''   | '20160324'
 'SMLF'     | '3A/32V'     | 'EMPTY'  | 'DK300WFU011'(!)         = 'End of Design' | 'End of Life'  | 'DK300WFU011'            |'F0603XB_EOL'| 'IO'  | 'FUSE SMD 3A 32V(FAST,0438003.WR,0603)'         | 'CHIP'         | ''          | ''   | '20160324'
 'SMLF'     | '1A/32V'     | 'IC'     | 'DK100WFU007'(!)         = ''              | ''             | 'DK100WFU007'            |'F0603XB'| 'IC'  | 'FUSE SMD 1A 32V(FAST,0438001.WR,0603)'         | 'CHIP'         | ''          | ''   | '20160324'
 'SMLF'     | '1A/32V'     | 'EMPTY'  | 'DK100WFU007'(!)         = ''              | ''             | 'DK100WFU007'            |'F0603XB'| 'IO'  | 'FUSE SMD 1A 32V(FAST,0438001.WR,0603)'         | 'CHIP'         | ''          | ''   | '20160324'
 'SMLF'     | '30A/125V'   | 'IC'     | 'DKV00XFU000'(!)         = ''              | ''             | 'DKV00XFU000'            |'F4012'| 'IC'  | 'FUSE SMD 30A 125V(FAST,UL/CSA)0456030.ER'      | 'CHIP'         | ''          | ''   | '20160401'
 'SMLF'     | '30A/125V'   | 'EMPTY'  | 'DKV00XFU000'(!)         = ''              | ''             | 'DKV00XFU000'            |'F4012'| 'IO'  | 'FUSE SMD 30A 125V(FAST,UL/CSA)0456030.ER'      | 'CHIP'         | ''          | ''   | '20160401'
 'SMLF'     | '10A/125V'   | 'IC'     | 'DKA00XFU007'(!)         = ''              | ''             | 'DKA00XFU007'            |'F2410'| 'IC'  | 'FUSE SMD 10A 125V(FAST,UL)0451010.MRSN'        | 'CHIP'         | ''          | ''   | '20160407'
 'SMLF'     | '10A/125V'   | 'EMPTY'  | 'DKA00XFU007'(!)         = ''              | ''             | 'DKA00XFU007'            |'F2410'| 'IO'  | 'FUSE SMD 10A 125V(FAST,UL)0451010.MRSN'        | 'CHIP'         | ''          | ''   | '20160407'
 'SMLF'     | '2A/125V'    | 'IC'     | 'DK200XFU001'(!)         = ''              | ''             | 'DK200XFU001'            |'F2410'| 'IC'  | 'FUSE SMD 2A 125V(FAST,UL)0451002.MRL'          | 'CHIP'         | ''          | ''   | '20161017'
 'SMLF'     | '2A/125V'    | 'EMPTY'  | 'DK200XFU001'(!)         = ''              | ''             | 'DK200XFU001'            |'F2410'| 'IO'  | 'FUSE SMD 2A 125V(FAST,UL)0451002.MRL'          | 'CHIP'         | ''          | ''   | '20161017'
 'SMLF'     | '5.0A/125V'  | 'IC'     | 'DK500XFU002'(!)         = ''              | ''             | 'DK500XFU002'            |'F2410_AF2'| 'IC'  | 'FUSE SMD 5.0A,125V(FAST,UL/PSE)AF2-5.00V'      | 'CHIP'         | ''          | ''   | '20170808'
 'SMLF'     | '5.0A/125V'  | 'EMPTY'  | 'DK500XFU002'(!)         = ''              | ''             | 'DK500XFU002'            |'F2410_AF2'| 'IO'  | 'FUSE SMD 5.0A,125V(FAST,UL/PSE)AF2-5.00V'      | 'CHIP'         | ''          | ''   | '20170808'
 'SMLF'     | '3A/125V'    | 'IC'     | 'DK300XFU004'(!)         = ''              | ''             | 'DK300XFU004'            |'F2410_AF2'| 'IC'  | 'FUSE SMD 3A 125V(FAST,UL)AF2-3.00V125TM'       | 'CHIP'         | ''          | ''   | '20170808'
 'SMLF'     | '3A/125V'    | 'EMPTY'  | 'DK300XFU004'(!)         = ''              | ''             | 'DK300XFU004'            |'F2410_AF2'| 'IO'  | 'FUSE SMD 3A 125V(FAST,UL)AF2-3.00V125TM'       | 'CHIP'         | ''          | ''   | '20170808'
 'SMLF'     | '7A/125V'    | 'IC'     | 'DK700XFU001'(!)         = ''              | ''             | 'DK700XFU001'            |'F2410_AF2'| 'IC'  | 'FUSE SMD 7A 125V(FAST,UL)AF2-7.00V125TM'       | 'CHIP'         | ''          | ''   | '20170808'
 'SMLF'     | '7A/125V'    | 'EMPTY'  | 'DK700XFU001'(!)         = ''              | ''             | 'DK700XFU001'            |'F2410_AF2'| 'IO'  | 'FUSE SMD 7A 125V(FAST,UL)AF2-7.00V125TM'       | 'CHIP'         | ''          | ''   | '20170808'
 'SMLF'     | '3A/125V'    | 'IC'     | 'DK300XFU002'(!)         = ''              | ''             | 'DK300XFU002'            |'F2410'| 'IC'  | 'FUSE SMD 3A 125V(FAST,UL)0451003.MRL'          | 'CHIP'         | ''          | ''   | '20170809'
 'SMLF'     | '3A/125V'    | 'EMPTY'  | 'DK300XFU002'(!)         = ''              | ''             | 'DK300XFU002'            |'F2410'| 'IO'  | 'FUSE SMD 3A 125V(FAST,UL)0451003.MRL'          | 'CHIP'         | ''          | ''   | '20170809'
 'SMLF'     | '7A/125V'    | 'IC'     | 'DK700XFU000'(!)         = ''              | ''             | 'DK700XFU000'            |'F2410'| 'IC'  | 'FUSE SMD 7A 125V(FAST,UL)0451007.MRL'          | 'CHIP'         | ''          | ''   | '20170809'
 'SMLF'     | '7A/125V'    | 'EMPTY'  | 'DK700XFU000'(!)         = ''              | ''             | 'DK700XFU000'            |'F2410'| 'IO'  | 'FUSE SMD 7A 125V(FAST,UL)0451007.MRL'          | 'CHIP'         | ''          | ''   | '20170809'
 'SMLF'     | '3.15A/150V' | 'IC'     | 'DK315XFU000'(!)         = ''              | ''             | 'DK315XFU000'            |'F2410_25CF'| 'IC'  | 'FUSE SMD 3.15A 150V(FAST,UL)25CF 3.15AR1'      | 'CHIP'         | ''          | ''   | '20171023'
 'SMLF'     | '3.15A/150V' | 'EMPTY'  | 'DK315XFU000'(!)         = ''              | ''             | 'DK315XFU000'            |'F2410_25CF'| 'IO'  | 'FUSE SMD 3.15A 150V(FAST,UL)25CF 3.15AR1'      | 'CHIP'         | ''          | ''   | '20171023'
 'SMLF'     | '5A/150V'    | 'IC'     | 'DK500XFU003'(!)         = ''              | ''             | 'DK500XFU003'            |'F2410_25CF'| 'IC'  | 'FUSE SMD 5A 150V(FAST,UL)25CF 5AR12A4'         | 'CHIP'         | ''          | ''   | '20171023'
 'SMLF'     | '5A/150V'    | 'EMPTY'  | 'DK500XFU003'(!)         = ''              | ''             | 'DK500XFU003'            |'F2410_25CF'| 'IO'  | 'FUSE SMD 5A 150V(FAST,UL)25CF 5AR12A4'         | 'CHIP'         | ''          | ''   | '20171023'
 'SMLF'     | '0.5A/6V'    | 'IC'     | 'DK050TPU011'(!)         = ''              | ''             | 'DK050TPU011'            |'F1206XH_H30'| 'IC'  | 'FUSE SMD 0.5A,6V(POLY,1206L050YR)'             | 'CHIP'         | ''          | ''   | '20170809'
 'SMLF'     | '0.5A/6V'    | 'EMPTY'  | 'DK050TPU011'(!)         = ''              | ''             | 'DK050TPU011'            |'F1206XH_H30'| 'IO'  | 'FUSE SMD 0.5A,6V(POLY,1206L050YR)'             | 'CHIP'         | ''          | ''   | '20170809'
 'SMLF'     | '1.1A/6V'    | 'IC'     | 'DK110TPU013'(!)         = ''              | ''             | 'DK110TPU013'            |'F0805'| 'IC'  | 'FUSE SMD 1.1A 6V POLY(SPR-P110)'               | 'CHIP'         | ''          | ''   | '20140828'
 'SMLF'     | '1.1A/6V'    | 'EMPTY'  | 'DK110TPU013'(!)         = ''              | ''             | 'DK110TPU013'            |'F0805'| 'IO'  | 'FUSE SMD 1.1A 6V POLY(SPR-P110)'               | 'CHIP'         | ''          | ''   | '20140828'
 'SMLF'     | '100MA/150V' | 'IC'     | 'DK010XFU000'(!)         = ''              | ''             | 'DK010XFU000'            |'F2410_25CF'| 'IC'  | 'FUSE SMD 100MA 150V(FAST,UL)25CF 100MAR1'      | 'CHIP'         | ''          | ''   | '20180419'
 'SMLF'     | '100MA/150V' | 'EMPTY'  | 'DK010XFU000'(!)         = ''              | ''             | 'DK010XFU000'            |'F2410_25CF'| 'IO'  | 'FUSE SMD 100MA 150V(FAST,UL)25CF 100MAR1'      | 'CHIP'         | ''          | ''   | '20180419'
 'SMLF'     | '80A/75V'    | 'IC'     | 'DKZ00UNU000'(!)         = ''              | ''             | 'DKZ00UNU000'            |'F4439_0881'| 'IC'  | 'FUSE SMD 80A 75V(NORMAL,UL)0881080.UR'         | 'CHIP'         | ''          | ''   | '20181108'
 'SMLF'     | '80A/75V'    | 'EMPTY'  | 'DKZ00UNU000'(!)         = ''              | ''             | 'DKZ00UNU000'            |'F4439_0881'| 'IO'  | 'FUSE SMD 80A 75V(NORMAL,UL)0881080.UR'         | 'CHIP'         | ''          | ''   | '20181108'
 'SMLF'     | '0.1A/30V'   | 'IC'     | 'DK010WPU000'(!)         = ''              | ''             | 'DK010WPU000'            |'F1210XA'| 'IC'  | 'FUSE SMD 0.1A,30V(POLY,UL/TUV)1210L010WR'      | 'CHIP'         | ''          | ''   | '20190104'
 'SMLF'     | '0.1A/30V'   | 'EMPTY'  | 'DK010WPU000'(!)         = ''              | ''             | 'DK010WPU000'            |'F1210XA'| 'IO'  | 'FUSE SMD 0.1A,30V(POLY,UL/TUV)1210L010WR'      | 'CHIP'         | ''          | ''   | '20190104'
 'SMLF'     | '1.5A/12V'   | 'IC'     | 'DK150SPU000'(!)         = 'End of Design' | 'Comp-Approve' | 'DK150SPU000'            |'F1812XF'| 'IC'  | 'FUSE SMD1.5A 12V POLY(MINISMDC150F/12)'        | 'CHIP'         | ''          | ''   | '20190304'
 'SMLF'     | '1.5A/12V'   | 'EMPTY'  | 'DK150SPU000'(!)         = 'End of Design' | 'Comp-Approve' | 'DK150SPU000'            |'F1812XF'| 'IO'  | 'FUSE SMD1.5A 12V POLY(MINISMDC150F/12)'        | 'CHIP'         | ''          | ''   | '20190304'
 'SMLF'     | '2.6A/16V'   | 'IC'     | 'DK260SPU000'(!)         = 'End of Design' | 'Comp-Approve' | 'DK260SPU000'            |'F1812XF_H60'| 'IC'  | 'FUSE SMD 2.6A 16V POLY(MINISMDC260F/16-2'      | 'CHIP'         | ''          | ''   | '20190304'
 'SMLF'     | '2.6A/16V'   | 'EMPTY'  | 'DK260SPU000'(!)         = 'End of Design' | 'Comp-Approve' | 'DK260SPU000'            |'F1812XF_H60'| 'IO'  | 'FUSE SMD 2.6A 16V POLY(MINISMDC260F/16-2'      | 'CHIP'         | ''          | ''   | '20190304'
 'SMLF'     | '40A/125V'   | 'IC'     | 'DKZ00XFU000'(!)         = ''              | ''             | 'DKZ00XFU000'            |'F4818'| 'IC'  | 'FUSE SMD 40A 125V(FAST,UL)0456040.DRSD'        | 'CHIP'         | ''          | ''   | '20190418'
 'SMLF'     | '40A/125V'   | 'EMPTY'  | 'DKZ00XFU000'(!)         = ''              | ''             | 'DKZ00XFU000'            |'F4818'| 'IO'  | 'FUSE SMD 40A 125V(FAST,UL)0456040.DRSD'        | 'CHIP'         | ''          | ''   | '20190418'
 'SMLF'     | '1.1A/16V'   | 'IC'     | 'DK110TPU005'(!)         = ''              | ''             | 'DK110TPU005'            |'F1812_1-25'| 'IC'  | 'FUSE SMD 1.1A 16V POLY(SMD1812P110TF/16)'      | 'CHIP'         | ''          | ''   | '20200102'
 'SMLF'     | '1.1A/16V'   | 'EMPTY'  | 'DK110TPU005'(!)         = ''              | ''             | 'DK110TPU005'            |'F1812_1-25'| 'IO'  | 'FUSE SMD 1.1A 16V POLY(SMD1812P110TF/16)'      | 'CHIP'         | ''          | ''   | '20200102'
 'SMLF'     | '2A/32V'     | 'IC'     | 'DK200WFU014'(!)         = ''              | ''             | 'DK200WFU014'            |'F0603XD'| 'IC'  | 'FUSE SMD 2A 32V(FAST,UL) 0686F2000-01'         | 'CHIP'         | ''          | ''   | '20200306'
 'SMLF'     | '2A/32V'     | 'EMPTY'  | 'DK200WFU014'(!)         = ''              | ''             | 'DK200WFU014'            |'F0603XD'| 'IO'  | 'FUSE SMD 2A 32V(FAST,UL) 0686F2000-01'         | 'CHIP'         | ''          | ''   | '20200306'
 'SMLF'     | '7.5A/6V'    | 'IC'     | 'DK750TPU000'(!)         = ''              | ''             | 'DK750TPU000'            |'F1210XA_H40'| 'IC'  | 'FUSE SMD 7.5A 6V POLY(SMD1210P750SLR)'         | 'CHIP'         | ''          | ''   | '20200424'
 'SMLF'     | '7.5A/6V'    | 'EMPTY'  | 'DK750TPU000'(!)         = ''              | ''             | 'DK750TPU000'            |'F1210XA_H40'| 'IO'  | 'FUSE SMD 7.5A 6V POLY(SMD1210P750SLR)'         | 'CHIP'         | ''          | ''   | '20200424'
 'SMLF'     | '1.5A/8V'    | 'IC'     | 'DK150TPU009'(!)         = ''              | ''             | 'DK150TPU009'            |'F1206XH_H40'| 'IC'  | 'FUSE SMD 1.5A,8V(POLY,1206L150THWR)'           | 'CHIP'         | ''          | ''   | '20200526'
 'SMLF'     | '1.5A/8V'    | 'EMPTY'  | 'DK150TPU009'(!)         = ''              | ''             | 'DK150TPU009'            |'F1206XH_H40'| 'IO'  | 'FUSE SMD 1.5A,8V(POLY,1206L150THWR)'           | 'CHIP'         | ''          | ''   | '20200526'
 'SMLF'     | '1A/50V'     | 'IC'     | 'DK100ZHU000'(!)         = ''              | ''             | 'DK100ZHU000'            |'F1206XC'| 'IC'  | 'FUSE SMD1A 50V(HIGH INRUSH,UL)0440001.WR'      | 'CHIP'         | ''          | ''   | '20210311'
 'SMLF'     | '1A/50V'     | 'EMPTY'  | 'DK100ZHU000'(!)         = ''              | ''             | 'DK100ZHU000'            |'F1206XC'| 'IO'  | 'FUSE SMD1A 50V(HIGH INRUSH,UL)0440001.WR'      | 'CHIP'         | ''          | ''   | '20210311'
 'SMLF'     | '1A/75V'     | 'IC'     | 'DK100UHU000'(!)         = ''              | ''             | 'DK100UHU000'            |'F1206XE'| 'IC'  | 'FUSE SMD1A 75V(HIGH INRUSH,UL)0458001.DR'      | 'CHIP'         | ''          | ''   | '20210317'
 'SMLF'     | '1A/75V'     | 'EMPTY'  | 'DK100UHU000'(!)         = ''              | ''             | 'DK100UHU000'            |'F1206XE'| 'IO'  | 'FUSE SMD1A 75V(HIGH INRUSH,UL)0458001.DR'      | 'CHIP'         | ''          | ''   | '20210317'
 'SMLF'     | '100A/75V'   | 'IC'     | 'DKA00UHU000'(!)         = ''              | ''             | 'DKA00UHU000'            |'F4439_0881'| 'IC'  | 'FUSE SMD 100A 75V(HIGH INRUSH)0881100.UR'      | 'CHIP'         | ''          | ''   | '20210407'
 'SMLF'     | '100A/75V'   | 'EMPTY'  | 'DKA00UHU000'(!)         = ''              | ''             | 'DKA00UHU000'            |'F4439_0881'| 'IO'  | 'FUSE SMD 100A 75V(HIGH INRUSH)0881100.UR'      | 'CHIP'         | ''          | ''   | '20210407'
 'SMLF'     | '2.6A/6V'    | 'IC'     | 'DK260TPU008'(!)         = ''              | ''             | 'DK260TPU008'            |'F0805'| 'IC'  | 'FUSE SMD 2.6A 6V POLY(SMD0805P260SLRT)'        | 'CHIP'         | ''          | ''   | '20210519'
 'SMLF'     | '2.6A/6V'    | 'EMPTY'  | 'DK260TPU008'(!)         = ''              | ''             | 'DK260TPU008'            |'F0805'| 'IO'  | 'FUSE SMD 2.6A 6V POLY(SMD0805P260SLRT)'        | 'CHIP'         | ''          | ''   | '20210519'
 'SMLF'     | '3A/6V'      | 'IC'     | 'DK300TPU014'(!)         = ''              | ''             | 'DK300TPU014'            |'F0603_H40'| 'IC'  | 'FUSE SMD 3A 6V POLY(SMD0603P300SLR)'           | 'CHIP'         | ''          | ''   | '20210617'
 'SMLF'     | '3A/6V'      | 'EMPTY'  | 'DK300TPU014'(!)         = ''              | ''             | 'DK300TPU014'            |'F0603_H40'| 'IO'  | 'FUSE SMD 3A 6V POLY(SMD0603P300SLR)'           | 'CHIP'         | ''          | ''   | '20210617'
 'SMLF'     | '1.5A/125V'  | 'IC'     | 'DK150XFU006'(!)         = ''              | ''             | 'DK150XFU006'            |'F2410'| 'IC'  | 'FUSE SMD 1.5A 125V(FAST,UL)045101.5MRL'        | 'CHIP'         | ''          | ''   | '20210913'
 'SMLF'     | '1.5A/125V'  | 'EMPTY'  | 'DK150XFU006'(!)         = ''              | ''             | 'DK150XFU006'            |'F2410'| 'IO'  | 'FUSE SMD 1.5A 125V(FAST,UL)045101.5MRL'        | 'CHIP'         | ''          | ''   | '20210913'
 'SMLF'     | '20A/125V'   | 'IC'     | 'DKK00XFU000'(!)         = ''              | ''             | 'DKK00XFU000'            |'F4012'| 'IC'  | 'FUSE SMD 20A/125V(FAST,UL/CSA)'                | 'CHIP'         | ''          | ''   | '20211207'
 'SMLF'     | '20A/125V'   | 'EMPTY'  | 'DKK00XFU000'(!)         = ''              | ''             | 'DKK00XFU000'            |'F4012'| 'IO'  | 'FUSE SMD 20A/125V(FAST,UL/CSA)'                | 'CHIP'         | ''          | ''   | '20211207'
 'SMLF'     | '1.5A/125V'  | 'IC'     | 'DK150XFU005'(!)         = ''              | ''             | 'DK150XFU005'            |'F2410'| 'IC'  | 'FUSE SMD 1.5A 125V(FAST,UL)0679L1500 AEC'      | 'CHIP'         | ''          | ''   | '20211215'
 'SMLF'     | '1.5A/125V'  | 'EMPTY'  | 'DK150XFU005'(!)         = ''              | ''             | 'DK150XFU005'            |'F2410'| 'IO'  | 'FUSE SMD 1.5A 125V(FAST,UL)0679L1500 AEC'      | 'CHIP'         | ''          | ''   | '20211215'
 'SMLF'     | '2A/6V'      | 'IC'     | 'DK200TPU008'(!)         = 'End of Design' | 'Comp-Approve' | 'DK200TPU008'            |'F1206XH_H63'| 'IC'  | 'FUSE SMD 2A 6V(POLY,1206L200PR)'               | 'CHIP'         | ''          | ''   | '20220429'
 'SMLF'     | '2A/6V'      | 'EMPTY'  | 'DK200TPU008'(!)         = 'End of Design' | 'Comp-Approve' | 'DK200TPU008'            |'F1206XH_H63'| 'IO'  | 'FUSE SMD 2A 6V(POLY,1206L200PR)'               | 'CHIP'         | ''          | ''   | '20220429'
 'SMLF'     | '2A/6V'      | 'IC'     | 'DK200TPU016'(!)         = ''              | ''             | 'DK200TPU016'            |'F1206XH'| 'IC'  | 'FUSE SMD 2A 6V POLY(SMD1206P200SLR)'           | 'CHIP'         | ''          | ''   | '20220506'
 'SMLF'     | '2A/6V'      | 'EMPTY'  | 'DK200TPU016'(!)         = ''              | ''             | 'DK200TPU016'            |'F1206XH'| 'IO'  | 'FUSE SMD 2A 6V POLY(SMD1206P200SLR)'           | 'CHIP'         | ''          | ''   | '20220506'
 'SMLF'     | '0.75A/65V'  | 'IC'     | 'DK075UFU000'(!)         = ''              | ''             | 'DK075UFU000'            |'F0603XE'| 'IC'  | 'FUSE SMD 0.75A 65V(FAST,T0603FF0750TM)'        | 'CHIP'         | ''          | ''   | '20220609'
 'SMLF'     | '0.75A/65V'  | 'EMPTY'  | 'DK075UFU000'(!)         = ''              | ''             | 'DK075UFU000'            |'F0603XE'| 'IO'  | 'FUSE SMD 0.75A 65V(FAST,T0603FF0750TM)'        | 'CHIP'         | ''          | ''   | '20220609'
 'SMLF'     | '20A/125V'   | 'IC'     | 'DKK00XFU001'(!)         = ''              | ''             | 'DKK00XFU001'            |'F4012XA'| 'IC'  | 'FUSE SMD 20A/125V(FAST,UL)1025HC20-RTR'        | 'CHIP'         | ''          | ''   | '20221205'
 'SMLF'     | '20A/125V'   | 'EMPTY'  | 'DKK00XFU001'(!)         = ''              | ''             | 'DKK00XFU001'            |'F4012XA'| 'IO'  | 'FUSE SMD 20A/125V(FAST,UL)1025HC20-RTR'        | 'CHIP'         | ''          | ''   | '20221205'
 'SMLF'     | '0.25A/9V'   | 'IC'     | 'DK025TPU002'(!)         = ''              | ''             | 'DK025TPU002'            |'F0603_H30'| 'IC'  | 'FUSE SMD 0.25A 9V POLY(0603L025YR)'            | 'CHIP'         | ''          | ''   | '20230103'
 'SMLF'     | '0.25A/9V'   | 'EMPTY'  | 'DK025TPU002'(!)         = ''              | ''             | 'DK025TPU002'            |'F0603_H30'| 'IO'  | 'FUSE SMD 0.25A 9V POLY(0603L025YR)'            | 'CHIP'         | ''          | ''   | '20230103'

END_PART

END.

